(kicad_pcb
	(version 20260206)
	(generator "pcbnew")
	(generator_version "10.0")
	(general
		(thickness 1.6)
		(legacy_teardrops no)
	)
	(paper "A4")
	(title_block
		(title "01162023_DA0F0TEBIF0_F0T_Expander_BD_F_brd_V02_OCP.brd")
		(comment 1 "Grand Teton / footprints 3232-3238 of 9728")
	)
	(layers
		(0 "F.Cu" signal "TOP")
		(4 "In1.Cu" signal "GND")
		(6 "In2.Cu" signal "VCC")
		(8 "In3.Cu" signal "VCC1")
		(10 "In4.Cu" signal "GND1")
		(12 "In5.Cu" signal "IN1")
		(14 "In6.Cu" signal "GND2")
		(16 "In7.Cu" signal "IN2")
		(18 "In8.Cu" signal "GND3")
		(20 "In9.Cu" signal "IN3")
		(22 "In10.Cu" signal "GND4")
		(24 "In11.Cu" signal "IN4")
		(26 "In12.Cu" signal "GND5")
		(28 "In13.Cu" signal "IN5")
		(30 "In14.Cu" signal "GND6")
		(32 "In15.Cu" signal "IN6")
		(34 "In16.Cu" signal "GND7")
		(2 "B.Cu" signal "BOTTOM")
		(9 "F.Adhes" user "F.Adhesive")
		(11 "B.Adhes" user "B.Adhesive")
		(13 "F.Paste" user "Package Geometry/Pastemask Top")
		(15 "B.Paste" user "Package Geometry/Pastemask Bottom")
		(5 "F.SilkS" user "Ref Des/Silkscreen Top")
		(7 "B.SilkS" user "Ref Des/Silkscreen Bottom")
		(1 "F.Mask" user "Board Geometry/Soldermask Top")
		(3 "B.Mask" user "Board Geometry/Soldermask Bottom")
		(17 "Dwgs.User" user "User.Drawings")
		(19 "Cmts.User" user "User.Comments")
		(21 "Eco1.User" user "User.Eco1")
		(23 "Eco2.User" user "User.Eco2")
		(25 "Edge.Cuts" user "Board Geometry/Outline")
		(27 "Margin" user)
		(31 "F.CrtYd" user "Package Geometry/Place Bound Top")
		(29 "B.CrtYd" user "Package Geometry/Place Bound Bottom")
		(35 "F.Fab" user "Ref Des/Assembly Top")
		(33 "B.Fab" user "Ref Des/Assembly Bottom")
	)
	(footprint ""
		(layer "F.Cu")
		(at 58.995056 -96.702372 180)
		(property "Reference" "R98"
			(at 0 0 180)
			(layer "F.SilkS")
			(hide yes)
			(effects
				(font
					(size 1.27 1.27)
				)
			)
		)
		(property "Value" ""
			(at 0 0 180)
			(layer "F.Fab")
			(effects
				(font
					(size 1.27 1.27)
				)
			)
		)
		(duplicate_pad_numbers_are_jumpers no)
		(fp_line
			(start 0.7874 0.4064)
			(end -0.7874 0.4064)
			(stroke
				(width 0.1524)
				(type default)
			)
			(layer "F.SilkS")
		)
		(fp_line
			(start 0.7874 -0.4064)
			(end 0.7874 0.4064)
			(stroke
				(width 0.1524)
				(type default)
			)
			(layer "F.SilkS")
		)
		(fp_line
			(start -0.7874 0.4064)
			(end -0.7874 -0.4064)
			(stroke
				(width 0.1524)
				(type default)
			)
			(layer "F.SilkS")
		)
		(fp_line
			(start -0.7874 -0.4064)
			(end 0.7874 -0.4064)
			(stroke
				(width 0.1524)
				(type default)
			)
			(layer "F.SilkS")
		)
		(fp_line
			(start 0.67945 0.3048)
			(end 0.120396 0.3048)
			(stroke
				(width 0.1)
				(type default)
			)
			(layer "F.Fab")
		)
		(fp_line
			(start 0.67945 -0.3048)
			(end 0.67945 0.3048)
			(stroke
				(width 0.1)
				(type default)
			)
			(layer "F.Fab")
		)
		(fp_line
			(start 0.12065 -0.2794)
			(end 0.12065 -0.3048)
			(stroke
				(width 0.1)
				(type default)
			)
			(layer "F.Fab")
		)
		(fp_line
			(start 0.12065 -0.3048)
			(end 0.67945 -0.3048)
			(stroke
				(width 0.1)
				(type default)
			)
			(layer "F.Fab")
		)
		(fp_line
			(start 0.120396 0.3048)
			(end 0.120396 0.2794)
			(stroke
				(width 0.1)
				(type default)
			)
			(layer "F.Fab")
		)
		(fp_line
			(start 0.120396 0.2794)
			(end -0.12065 0.2794)
			(stroke
				(width 0.1)
				(type default)
			)
			(layer "F.Fab")
		)
		(fp_line
			(start -0.12065 0.3048)
			(end -0.67945 0.3048)
			(stroke
				(width 0.1)
				(type default)
			)
			(layer "F.Fab")
		)
		(fp_line
			(start -0.12065 0.2794)
			(end -0.12065 0.3048)
			(stroke
				(width 0.1)
				(type default)
			)
			(layer "F.Fab")
		)
		(fp_line
			(start -0.12065 -0.2794)
			(end 0.12065 -0.2794)
			(stroke
				(width 0.1)
				(type default)
			)
			(layer "F.Fab")
		)
		(fp_line
			(start -0.12065 -0.305054)
			(end -0.12065 -0.2794)
			(stroke
				(width 0.1)
				(type default)
			)
			(layer "F.Fab")
		)
		(fp_line
			(start -0.67945 0.3048)
			(end -0.67945 -0.305054)
			(stroke
				(width 0.1)
				(type default)
			)
			(layer "F.Fab")
		)
		(fp_line
			(start -0.67945 -0.305054)
			(end -0.12065 -0.305054)
			(stroke
				(width 0.1)
				(type default)
			)
			(layer "F.Fab")
		)
		(pad "1" smd circle
			(at -0.40005 0 180)
			(size 0 0)
			(layers "F.Cu" "F.Mask" "F.Paste")
			(net "RST_NIC1_PERST2_R_N")
		)
		(pad "2" smd circle
			(at 0.40005 0 180)
			(size 0 0)
			(layers "F.Cu" "F.Mask" "F.Paste")
			(net "RST_HP_NIC1_BUF_N")
		)
	)
	(footprint ""
		(layer "F.Cu")
		(at 440.359292 -350.098614 90)
		(property "Reference" "C2469"
			(at 0 0 90)
			(layer "F.SilkS")
			(hide yes)
			(effects
				(font
					(size 1.27 1.27)
				)
			)
		)
		(property "Value" ""
			(at 0 0 90)
			(layer "F.Fab")
			(effects
				(font
					(size 1.27 1.27)
				)
			)
		)
		(duplicate_pad_numbers_are_jumpers no)
		(fp_line
			(start 0.299974 -0.150114)
			(end 0.299974 0.150114)
			(stroke
				(width 0.1)
				(type default)
			)
			(layer "F.Fab")
		)
		(fp_line
			(start -0.299974 -0.150114)
			(end 0.299974 -0.150114)
			(stroke
				(width 0.1)
				(type default)
			)
			(layer "F.Fab")
		)
		(fp_line
			(start 0.299974 0.150114)
			(end -0.299974 0.150114)
			(stroke
				(width 0.1)
				(type default)
			)
			(layer "F.Fab")
		)
		(fp_line
			(start -0.299974 0.150114)
			(end -0.299974 -0.150114)
			(stroke
				(width 0.1)
				(type default)
			)
			(layer "F.Fab")
		)
		(pad "1" smd rect
			(at -0.2667 0 90)
			(size 0.3048 0.381)
			(layers "F.Cu" "F.Mask" "F.Paste")
			(net "P5E_PEX3_STN4_TX_DP<64>")
		)
		(pad "2" smd rect
			(at 0.2667 0 90)
			(size 0.3048 0.381)
			(layers "F.Cu" "F.Mask" "F.Paste")
			(net "P5E_PEX3_STN4_TX_C_DP<64>")
		)
	)
	(footprint ""
		(layer "F.Cu")
		(at 17.191736 -152.71115 90)
		(property "Reference" "R680"
			(at 0 0 90)
			(layer "F.SilkS")
			(hide yes)
			(effects
				(font
					(size 1.27 1.27)
				)
			)
		)
		(property "Value" ""
			(at 0 0 90)
			(layer "F.Fab")
			(effects
				(font
					(size 1.27 1.27)
				)
			)
		)
		(duplicate_pad_numbers_are_jumpers no)
		(fp_line
			(start 0.7874 -0.4064)
			(end 0.7874 0.4064)
			(stroke
				(width 0.1524)
				(type default)
			)
			(layer "F.SilkS")
		)
		(fp_line
			(start -0.7874 -0.4064)
			(end 0.7874 -0.4064)
			(stroke
				(width 0.1524)
				(type default)
			)
			(layer "F.SilkS")
		)
		(fp_line
			(start 0.7874 0.4064)
			(end -0.7874 0.4064)
			(stroke
				(width 0.1524)
				(type default)
			)
			(layer "F.SilkS")
		)
		(fp_line
			(start -0.7874 0.4064)
			(end -0.7874 -0.4064)
			(stroke
				(width 0.1524)
				(type default)
			)
			(layer "F.SilkS")
		)
		(fp_line
			(start -0.12065 -0.305054)
			(end -0.12065 -0.2794)
			(stroke
				(width 0.1)
				(type default)
			)
			(layer "F.Fab")
		)
		(fp_line
			(start -0.67945 -0.305054)
			(end -0.12065 -0.305054)
			(stroke
				(width 0.1)
				(type default)
			)
			(layer "F.Fab")
		)
		(fp_line
			(start 0.67945 -0.3048)
			(end 0.67945 0.3048)
			(stroke
				(width 0.1)
				(type default)
			)
			(layer "F.Fab")
		)
		(fp_line
			(start 0.12065 -0.3048)
			(end 0.67945 -0.3048)
			(stroke
				(width 0.1)
				(type default)
			)
			(layer "F.Fab")
		)
		(fp_line
			(start 0.12065 -0.2794)
			(end 0.12065 -0.3048)
			(stroke
				(width 0.1)
				(type default)
			)
			(layer "F.Fab")
		)
		(fp_line
			(start -0.12065 -0.2794)
			(end 0.12065 -0.2794)
			(stroke
				(width 0.1)
				(type default)
			)
			(layer "F.Fab")
		)
		(fp_line
			(start 0.120396 0.2794)
			(end -0.12065 0.2794)
			(stroke
				(width 0.1)
				(type default)
			)
			(layer "F.Fab")
		)
		(fp_line
			(start -0.12065 0.2794)
			(end -0.12065 0.3048)
			(stroke
				(width 0.1)
				(type default)
			)
			(layer "F.Fab")
		)
		(fp_line
			(start 0.67945 0.3048)
			(end 0.120396 0.3048)
			(stroke
				(width 0.1)
				(type default)
			)
			(layer "F.Fab")
		)
		(fp_line
			(start 0.120396 0.3048)
			(end 0.120396 0.2794)
			(stroke
				(width 0.1)
				(type default)
			)
			(layer "F.Fab")
		)
		(fp_line
			(start -0.12065 0.3048)
			(end -0.67945 0.3048)
			(stroke
				(width 0.1)
				(type default)
			)
			(layer "F.Fab")
		)
		(fp_line
			(start -0.67945 0.3048)
			(end -0.67945 -0.305054)
			(stroke
				(width 0.1)
				(type default)
			)
			(layer "F.Fab")
		)
		(pad "1" smd circle
			(at -0.40005 0 90)
			(size 0 0)
			(layers "F.Cu" "F.Mask" "F.Paste")
			(net "P3V3_AUX")
		)
		(pad "2" smd circle
			(at 0.40005 0 90)
			(size 0 0)
			(layers "F.Cu" "F.Mask" "F.Paste")
			(net "NIC_ADC_ALERT_N")
		)
	)
	(footprint ""
		(layer "F.Cu")
		(at 317.971678 -24.807418)
		(property "Reference" "R444"
			(at 0 0 0)
			(layer "F.SilkS")
			(hide yes)
			(effects
				(font
					(size 1.27 1.27)
				)
			)
		)
		(property "Value" ""
			(at 0 0 0)
			(layer "F.Fab")
			(effects
				(font
					(size 1.27 1.27)
				)
			)
		)
		(duplicate_pad_numbers_are_jumpers no)
		(fp_line
			(start -0.7874 -0.4064)
			(end 0.7874 -0.4064)
			(stroke
				(width 0.1524)
				(type default)
			)
			(layer "F.SilkS")
		)
		(fp_line
			(start -0.7874 0.4064)
			(end -0.7874 -0.4064)
			(stroke
				(width 0.1524)
				(type default)
			)
			(layer "F.SilkS")
		)
		(fp_line
			(start 0.7874 -0.4064)
			(end 0.7874 0.4064)
			(stroke
				(width 0.1524)
				(type default)
			)
			(layer "F.SilkS")
		)
		(fp_line
			(start 0.7874 0.4064)
			(end -0.7874 0.4064)
			(stroke
				(width 0.1524)
				(type default)
			)
			(layer "F.SilkS")
		)
		(fp_line
			(start -0.67945 -0.305054)
			(end -0.12065 -0.305054)
			(stroke
				(width 0.1)
				(type default)
			)
			(layer "F.Fab")
		)
		(fp_line
			(start -0.67945 0.3048)
			(end -0.67945 -0.305054)
			(stroke
				(width 0.1)
				(type default)
			)
			(layer "F.Fab")
		)
		(fp_line
			(start -0.12065 -0.305054)
			(end -0.12065 -0.2794)
			(stroke
				(width 0.1)
				(type default)
			)
			(layer "F.Fab")
		)
		(fp_line
			(start -0.12065 -0.2794)
			(end 0.12065 -0.2794)
			(stroke
				(width 0.1)
				(type default)
			)
			(layer "F.Fab")
		)
		(fp_line
			(start -0.12065 0.2794)
			(end -0.12065 0.3048)
			(stroke
				(width 0.1)
				(type default)
			)
			(layer "F.Fab")
		)
		(fp_line
			(start -0.12065 0.3048)
			(end -0.67945 0.3048)
			(stroke
				(width 0.1)
				(type default)
			)
			(layer "F.Fab")
		)
		(fp_line
			(start 0.120396 0.2794)
			(end -0.12065 0.2794)
			(stroke
				(width 0.1)
				(type default)
			)
			(layer "F.Fab")
		)
		(fp_line
			(start 0.120396 0.3048)
			(end 0.120396 0.2794)
			(stroke
				(width 0.1)
				(type default)
			)
			(layer "F.Fab")
		)
		(fp_line
			(start 0.12065 -0.3048)
			(end 0.67945 -0.3048)
			(stroke
				(width 0.1)
				(type default)
			)
			(layer "F.Fab")
		)
		(fp_line
			(start 0.12065 -0.2794)
			(end 0.12065 -0.3048)
			(stroke
				(width 0.1)
				(type default)
			)
			(layer "F.Fab")
		)
		(fp_line
			(start 0.67945 -0.3048)
			(end 0.67945 0.3048)
			(stroke
				(width 0.1)
				(type default)
			)
			(layer "F.Fab")
		)
		(fp_line
			(start 0.67945 0.3048)
			(end 0.120396 0.3048)
			(stroke
				(width 0.1)
				(type default)
			)
			(layer "F.Fab")
		)
		(pad "1" smd circle
			(at -0.40005 0)
			(size 0 0)
			(layers "F.Cu" "F.Mask" "F.Paste")
			(net "P3V3_SSD11")
		)
		(pad "2" smd circle
			(at 0.40005 0)
			(size 0 0)
			(layers "F.Cu" "F.Mask" "F.Paste")
			(net "PU_CLKREQ11")
		)
	)
	(footprint ""
		(layer "F.Cu")
		(at 436.120032 -289.230816 -90)
		(property "Reference" "R3998"
			(at 0 0 270)
			(layer "F.SilkS")
			(hide yes)
			(effects
				(font
					(size 1.27 1.27)
				)
			)
		)
		(property "Value" ""
			(at 0 0 270)
			(layer "F.Fab")
			(effects
				(font
					(size 1.27 1.27)
				)
			)
		)
		(duplicate_pad_numbers_are_jumpers no)
		(fp_line
			(start -0.7874 0.4064)
			(end -0.7874 -0.4064)
			(stroke
				(width 0.1524)
				(type default)
			)
			(layer "F.SilkS")
		)
		(fp_line
			(start 0.7874 0.4064)
			(end -0.7874 0.4064)
			(stroke
				(width 0.1524)
				(type default)
			)
			(layer "F.SilkS")
		)
		(fp_line
			(start -0.7874 -0.4064)
			(end 0.7874 -0.4064)
			(stroke
				(width 0.1524)
				(type default)
			)
			(layer "F.SilkS")
		)
		(fp_line
			(start 0.7874 -0.4064)
			(end 0.7874 0.4064)
			(stroke
				(width 0.1524)
				(type default)
			)
			(layer "F.SilkS")
		)
		(fp_line
			(start -0.67945 0.3048)
			(end -0.67945 -0.305054)
			(stroke
				(width 0.1)
				(type default)
			)
			(layer "F.Fab")
		)
		(fp_line
			(start -0.12065 0.3048)
			(end -0.67945 0.3048)
			(stroke
				(width 0.1)
				(type default)
			)
			(layer "F.Fab")
		)
		(fp_line
			(start 0.120396 0.3048)
			(end 0.120396 0.2794)
			(stroke
				(width 0.1)
				(type default)
			)
			(layer "F.Fab")
		)
		(fp_line
			(start 0.67945 0.3048)
			(end 0.120396 0.3048)
			(stroke
				(width 0.1)
				(type default)
			)
			(layer "F.Fab")
		)
		(fp_line
			(start -0.12065 0.2794)
			(end -0.12065 0.3048)
			(stroke
				(width 0.1)
				(type default)
			)
			(layer "F.Fab")
		)
		(fp_line
			(start 0.120396 0.2794)
			(end -0.12065 0.2794)
			(stroke
				(width 0.1)
				(type default)
			)
			(layer "F.Fab")
		)
		(fp_line
			(start -0.12065 -0.2794)
			(end 0.12065 -0.2794)
			(stroke
				(width 0.1)
				(type default)
			)
			(layer "F.Fab")
		)
		(fp_line
			(start 0.12065 -0.2794)
			(end 0.12065 -0.3048)
			(stroke
				(width 0.1)
				(type default)
			)
			(layer "F.Fab")
		)
		(fp_line
			(start 0.12065 -0.3048)
			(end 0.67945 -0.3048)
			(stroke
				(width 0.1)
				(type default)
			)
			(layer "F.Fab")
		)
		(fp_line
			(start 0.67945 -0.3048)
			(end 0.67945 0.3048)
			(stroke
				(width 0.1)
				(type default)
			)
			(layer "F.Fab")
		)
		(fp_line
			(start -0.67945 -0.305054)
			(end -0.12065 -0.305054)
			(stroke
				(width 0.1)
				(type default)
			)
			(layer "F.Fab")
		)
		(fp_line
			(start -0.12065 -0.305054)
			(end -0.12065 -0.2794)
			(stroke
				(width 0.1)
				(type default)
			)
			(layer "F.Fab")
		)
		(pad "1" smd circle
			(at -0.40005 0 270)
			(size 0 0)
			(layers "F.Cu" "F.Mask" "F.Paste")
			(net "SMB_PEX3_HOST_LS_SDA")
		)
		(pad "2" smd circle
			(at 0.40005 0 270)
			(size 0 0)
			(layers "F.Cu" "F.Mask" "F.Paste")
			(net "P3V3_AUX")
		)
	)
	(footprint ""
		(layer "F.Cu")
		(at 126.210314 -121.661428 180)
		(property "Reference" "C2881"
			(at 0 0 180)
			(layer "F.SilkS")
			(hide yes)
			(effects
				(font
					(size 1.27 1.27)
				)
			)
		)
		(property "Value" ""
			(at 0 0 180)
			(layer "F.Fab")
			(effects
				(font
					(size 1.27 1.27)
				)
			)
		)
		(duplicate_pad_numbers_are_jumpers no)
		(fp_line
			(start 0.7874 0.4064)
			(end -0.7874 0.4064)
			(stroke
				(width 0.1524)
				(type default)
			)
			(layer "F.SilkS")
		)
		(fp_line
			(start 0.7874 -0.4064)
			(end 0.7874 0.4064)
			(stroke
				(width 0.1524)
				(type default)
			)
			(layer "F.SilkS")
		)
		(fp_line
			(start -0.7874 0.4064)
			(end -0.7874 -0.4064)
			(stroke
				(width 0.1524)
				(type default)
			)
			(layer "F.SilkS")
		)
		(fp_line
			(start -0.7874 -0.4064)
			(end 0.7874 -0.4064)
			(stroke
				(width 0.1524)
				(type default)
			)
			(layer "F.SilkS")
		)
		(fp_line
			(start 0.67945 0.3048)
			(end 0.120396 0.3048)
			(stroke
				(width 0.1)
				(type default)
			)
			(layer "F.Fab")
		)
		(fp_line
			(start 0.67945 -0.3048)
			(end 0.67945 0.3048)
			(stroke
				(width 0.1)
				(type default)
			)
			(layer "F.Fab")
		)
		(fp_line
			(start 0.12065 -0.2794)
			(end 0.12065 -0.3048)
			(stroke
				(width 0.1)
				(type default)
			)
			(layer "F.Fab")
		)
		(fp_line
			(start 0.12065 -0.3048)
			(end 0.67945 -0.3048)
			(stroke
				(width 0.1)
				(type default)
			)
			(layer "F.Fab")
		)
		(fp_line
			(start 0.120396 0.3048)
			(end 0.120396 0.2794)
			(stroke
				(width 0.1)
				(type default)
			)
			(layer "F.Fab")
		)
		(fp_line
			(start 0.120396 0.2794)
			(end -0.12065 0.2794)
			(stroke
				(width 0.1)
				(type default)
			)
			(layer "F.Fab")
		)
		(fp_line
			(start -0.12065 0.3048)
			(end -0.67945 0.3048)
			(stroke
				(width 0.1)
				(type default)
			)
			(layer "F.Fab")
		)
		(fp_line
			(start -0.12065 0.2794)
			(end -0.12065 0.3048)
			(stroke
				(width 0.1)
				(type default)
			)
			(layer "F.Fab")
		)
		(fp_line
			(start -0.12065 -0.2794)
			(end 0.12065 -0.2794)
			(stroke
				(width 0.1)
				(type default)
			)
			(layer "F.Fab")
		)
		(fp_line
			(start -0.12065 -0.305054)
			(end -0.12065 -0.2794)
			(stroke
				(width 0.1)
				(type default)
			)
			(layer "F.Fab")
		)
		(fp_line
			(start -0.67945 0.3048)
			(end -0.67945 -0.305054)
			(stroke
				(width 0.1)
				(type default)
			)
			(layer "F.Fab")
		)
		(fp_line
			(start -0.67945 -0.305054)
			(end -0.12065 -0.305054)
			(stroke
				(width 0.1)
				(type default)
			)
			(layer "F.Fab")
		)
		(pad "1" smd circle
			(at -0.40005 0 180)
			(size 0 0)
			(layers "F.Cu" "F.Mask" "F.Paste")
			(net "HP_NIC2_EN")
		)
		(pad "2" smd circle
			(at 0.40005 0 180)
			(size 0 0)
			(layers "F.Cu" "F.Mask" "F.Paste")
			(net "GND")
		)
	)
	(footprint ""
		(layer "F.Cu")
		(at 261.743698 -311.725564 45)
		(property "Reference" "R1350"
			(at 0 0 45)
			(layer "F.SilkS")
			(hide yes)
			(effects
				(font
					(size 1.27 1.27)
				)
			)
		)
		(property "Value" ""
			(at 0 0 45)
			(layer "F.Fab")
			(effects
				(font
					(size 1.27 1.27)
				)
			)
		)
		(duplicate_pad_numbers_are_jumpers no)
		(fp_line
			(start -0.787389 -0.406267)
			(end 0.787389 -0.406267)
			(stroke
				(width 0.1524)
				(type default)
			)
			(layer "F.SilkS")
		)
		(fp_line
			(start -0.787389 0.406267)
			(end -0.787389 -0.406267)
			(stroke
				(width 0.1524)
				(type default)
			)
			(layer "F.SilkS")
		)
		(fp_line
			(start 0.787389 -0.406267)
			(end 0.787389 0.406267)
			(stroke
				(width 0.1524)
				(type default)
			)
			(layer "F.SilkS")
		)
		(fp_line
			(start 0.787389 0.406267)
			(end -0.787389 0.406267)
			(stroke
				(width 0.1524)
				(type default)
			)
			(layer "F.SilkS")
		)
		(fp_line
			(start -0.679446 -0.305149)
			(end -0.120695 -0.304969)
			(stroke
				(width 0.1)
				(type default)
			)
			(layer "F.Fab")
		)
		(fp_line
			(start -0.120695 -0.304969)
			(end -0.120695 -0.279466)
			(stroke
				(width 0.1)
				(type default)
			)
			(layer "F.Fab")
		)
		(fp_line
			(start -0.120695 -0.279466)
			(end 0.120695 -0.279466)
			(stroke
				(width 0.1)
				(type default)
			)
			(layer "F.Fab")
		)
		(fp_line
			(start -0.679446 0.30479)
			(end -0.679446 -0.305149)
			(stroke
				(width 0.1)
				(type default)
			)
			(layer "F.Fab")
		)
		(fp_line
			(start 0.120515 -0.30479)
			(end 0.679446 -0.30479)
			(stroke
				(width 0.1)
				(type default)
			)
			(layer "F.Fab")
		)
		(fp_line
			(start 0.120695 -0.279466)
			(end 0.120515 -0.30479)
			(stroke
				(width 0.1)
				(type default)
			)
			(layer "F.Fab")
		)
		(fp_line
			(start -0.120695 0.279466)
			(end -0.120515 0.30479)
			(stroke
				(width 0.1)
				(type default)
			)
			(layer "F.Fab")
		)
		(fp_line
			(start -0.120515 0.30479)
			(end -0.679446 0.30479)
			(stroke
				(width 0.1)
				(type default)
			)
			(layer "F.Fab")
		)
		(fp_line
			(start 0.679446 -0.30479)
			(end 0.679446 0.30479)
			(stroke
				(width 0.1)
				(type default)
			)
			(layer "F.Fab")
		)
		(fp_line
			(start 0.120335 0.279466)
			(end -0.120695 0.279466)
			(stroke
				(width 0.1)
				(type default)
			)
			(layer "F.Fab")
		)
		(fp_line
			(start 0.120515 0.30479)
			(end 0.120335 0.279466)
			(stroke
				(width 0.1)
				(type default)
			)
			(layer "F.Fab")
		)
		(fp_line
			(start 0.679446 0.30479)
			(end 0.120515 0.30479)
			(stroke
				(width 0.1)
				(type default)
			)
			(layer "F.Fab")
		)
		(pad "1" smd circle
			(at -0.40005 0 45)
			(size 0 0)
			(layers "F.Cu" "F.Mask" "F.Paste")
			(net "GND")
		)
		(pad "2" smd circle
			(at 0.40005 0 45)
			(size 0 0)
			(layers "F.Cu" "F.Mask" "F.Paste")
			(net "PEX2_DBG_SEL1")
		)
	)
)
